(kicad_pcb
	(version 20240108)
	(generator "pcbnew")
	(generator_version "8.0")
	(general
		(thickness 1.62)
		(legacy_teardrops no)
	)
	(paper "A4")
	(title_block
		(title "Jetson Orin Baseboard")
		(date "2025-03-12")
		(rev "1.3.4")
		(company "Antmicro Ltd")
		(comment 1 "www.antmicro.com")
		(comment 9 "footprints 259-263 of 677")
	)
	(layers
		(0 "F.Cu" signal)
		(1 "In1.Cu" signal)
		(2 "In2.Cu" signal)
		(3 "In3.Cu" signal)
		(4 "In4.Cu" jumper)
		(5 "In5.Cu" signal)
		(6 "In6.Cu" signal)
		(31 "B.Cu" signal)
		(32 "B.Adhes" user "B.Adhesive")
		(33 "F.Adhes" user "F.Adhesive")
		(34 "B.Paste" user)
		(35 "F.Paste" user)
		(36 "B.SilkS" user "B.Silkscreen")
		(37 "F.SilkS" user "F.Silkscreen")
		(38 "B.Mask" user)
		(39 "F.Mask" user)
		(40 "Dwgs.User" user "User.Drawings")
		(41 "Cmts.User" user "User.Comments")
		(42 "Eco1.User" user "User.Eco1")
		(43 "Eco2.User" user "User.Eco2")
		(44 "Edge.Cuts" user)
		(45 "Margin" user)
		(46 "B.CrtYd" user "B.Courtyard")
		(47 "F.CrtYd" user "F.Courtyard")
		(48 "B.Fab" user)
		(49 "F.Fab" user)
	)
	(footprint "antmicro-footprints:R_0402_1005Metric"
		(layer "F.Cu")
		(at 68.27 86.47 180)
		(descr "Resistor SMD 0402")
		(tags "resistor SMD 0402")
		(property "Reference" "R3"
			(at -4.11 3.79 0)
			(layer "F.SilkS")
			(effects
				(font
					(size 0.7 0.7)
					(thickness 0.15)
				)
				(justify right top)
			)
		)
		(property "Value" "R_0R_0402"
			(at 0 1.4 0)
			(layer "F.Fab")
			(effects
				(font
					(size 0.7 0.7)
					(thickness 0.15)
				)
				(justify right top)
			)
		)
		(property "Footprint" "antmicro-footprints:R_0402_1005Metric"
			(at 0 0 0)
			(layer "F.Fab")
			(hide yes)
			(effects
				(font
					(size 1.27 1.27)
					(thickness 0.15)
				)
			)
		)
		(property "Datasheet" "https://industrial.panasonic.com/cdbs/www-data/pdf/RDA0000/AOA0000C301.pdf"
			(at 0 0 0)
			(layer "F.Fab")
			(hide yes)
			(effects
				(font
					(size 1.27 1.27)
					(thickness 0.15)
				)
			)
		)
		(property "Author" "Antmicro"
			(at -15.45 150.35 90)
			(layer "F.Fab")
			(hide yes)
			(effects
				(font
					(size 1 1)
					(thickness 0.15)
				)
			)
		)
		(property "Current" "1A"
			(at -15.45 150.35 90)
			(layer "F.Fab")
			(hide yes)
			(effects
				(font
					(size 1 1)
					(thickness 0.15)
				)
			)
		)
		(property "License" "Apache-2.0"
			(at -15.45 150.35 90)
			(layer "F.Fab")
			(hide yes)
			(effects
				(font
					(size 1 1)
					(thickness 0.15)
				)
			)
		)
		(property "MPN" "ERJ2GE0R00X"
			(at -15.45 150.35 90)
			(layer "F.Fab")
			(hide yes)
			(effects
				(font
					(size 1 1)
					(thickness 0.15)
				)
			)
		)
		(property "Manufacturer" "Panasonic"
			(at -15.45 150.35 90)
			(layer "F.Fab")
			(hide yes)
			(effects
				(font
					(size 1 1)
					(thickness 0.15)
				)
			)
		)
		(property "Tolerance" ""
			(at -15.45 150.35 90)
			(layer "F.Fab")
			(hide yes)
			(effects
				(font
					(size 1 1)
					(thickness 0.15)
				)
			)
		)
		(property "Val" "0R"
			(at -15.45 150.35 90)
			(layer "F.Fab")
			(hide yes)
			(effects
				(font
					(size 1 1)
					(thickness 0.15)
				)
			)
		)
		(sheetname "SoM")
		(sheetfile "som.kicad_sch")
		(attr smd)
		(fp_rect
			(start -0.925 -0.47)
			(end 0.925 0.47)
			(stroke
				(width 0.05)
				(type default)
			)
			(fill none)
			(layer "F.CrtYd")
		)
		(fp_rect
			(start -0.5 -0.25)
			(end 0.5 0.25)
			(stroke
				(width 0.15)
				(type solid)
			)
			(fill none)
			(layer "F.Fab")
		)
		(fp_text user "Author: Antmicro"
			(at -0.95 4.169 0)
			(layer "F.Fab")
			(hide yes)
			(effects
				(font
					(size 0.7 0.7)
					(thickness 0.15)
				)
				(justify right top)
			)
		)
		(fp_text user "${REFERENCE}"
			(at -0.95 3.168 0)
			(layer "F.Fab")
			(hide yes)
			(effects
				(font
					(size 0.7 0.7)
					(thickness 0.15)
				)
				(justify right top)
			)
		)
		(fp_text user "License: Apache-2.0"
			(at -0.95 5.169 0)
			(layer "F.Fab")
			(hide yes)
			(effects
				(font
					(size 0.7 0.7)
					(thickness 0.15)
				)
				(justify right top)
			)
		)
		(pad "1" smd roundrect
			(at -0.48 0 180)
			(size 0.59 0.64)
			(layers "F.Cu" "F.Paste" "F.Mask")
			(roundrect_rratio 0.25)
			(net 753 "Net-(J15H-GPIO13{slash}PWM)")
			(pintype "passive")
		)
		(pad "2" smd roundrect
			(at 0.48 0 180)
			(size 0.59 0.64)
			(layers "F.Cu" "F.Paste" "F.Mask")
			(roundrect_rratio 0.25)
			(net 84 "GPIO13")
			(pintype "passive")
		)
	)
	(footprint "antmicro-footprints:R_Array_4x0402"
		(layer "F.Cu")
		(at 147.8 95.5 -90)
		(property "Reference" "R64"
			(at 1.13 -1.63 -90)
			(layer "F.SilkS")
			(effects
				(font
					(size 0.7 0.7)
					(thickness 0.15)
				)
				(justify left bottom)
			)
		)
		(property "Value" "R_4x330R_0402_array"
			(at -1.5 2 -90)
			(layer "F.Fab")
			(effects
				(font
					(size 0.7 0.7)
					(thickness 0.15)
				)
				(justify left bottom)
			)
		)
		(property "Footprint" "antmicro-footprints:R_Array_4x0402"
			(at 0 0 -90)
			(layer "F.Fab")
			(hide yes)
			(effects
				(font
					(size 1.27 1.27)
					(thickness 0.15)
				)
			)
		)
		(property "Datasheet" "http://industrial.panasonic.com/cdbs/www-data/pdf/AOC0000/AOC0000C14.pdf"
			(at 0 0 -90)
			(layer "F.Fab")
			(hide yes)
			(effects
				(font
					(size 1.27 1.27)
					(thickness 0.15)
				)
			)
		)
		(property "Author" "Antmicro"
			(at 52.3 243.3 0)
			(layer "F.Fab")
			(hide yes)
			(effects
				(font
					(size 1 1)
					(thickness 0.15)
				)
			)
		)
		(property "License" "Apache-2.0"
			(at 52.3 243.3 0)
			(layer "F.Fab")
			(hide yes)
			(effects
				(font
					(size 1 1)
					(thickness 0.15)
				)
			)
		)
		(property "MPN" "EXB-28V331JX"
			(at 52.3 243.3 0)
			(layer "F.Fab")
			(hide yes)
			(effects
				(font
					(size 1 1)
					(thickness 0.15)
				)
			)
		)
		(property "Manufacturer" "Panasonic"
			(at 52.3 243.3 0)
			(layer "F.Fab")
			(hide yes)
			(effects
				(font
					(size 1 1)
					(thickness 0.15)
				)
			)
		)
		(property "Val" "R_4x330R_0402"
			(at 52.3 243.3 0)
			(layer "F.Fab")
			(hide yes)
			(effects
				(font
					(size 1 1)
					(thickness 0.15)
				)
			)
		)
		(sheetname "Peripherals")
		(sheetfile "peripherals.kicad_sch")
		(attr smd)
		(fp_line
			(start 1.167 0.498)
			(end 1.167 -0.5)
			(stroke
				(width 0.15)
				(type solid)
			)
			(layer "F.SilkS")
		)
		(fp_line
			(start -1.17 -0.5)
			(end -1.17 0.498)
			(stroke
				(width 0.15)
				(type solid)
			)
			(layer "F.SilkS")
		)
		(fp_rect
			(start -1.2 -0.9)
			(end 1.2 0.9)
			(stroke
				(width 0.05)
				(type solid)
			)
			(fill none)
			(layer "F.CrtYd")
		)
		(fp_line
			(start -1 0.498)
			(end -1 -0.5)
			(stroke
				(width 0.15)
				(type solid)
			)
			(layer "F.Fab")
		)
		(fp_line
			(start 0.998 0.498)
			(end -1 0.498)
			(stroke
				(width 0.15)
				(type solid)
			)
			(layer "F.Fab")
		)
		(fp_line
			(start -1 -0.5)
			(end 0.998 -0.5)
			(stroke
				(width 0.15)
				(type solid)
			)
			(layer "F.Fab")
		)
		(fp_line
			(start 0.998 -0.5)
			(end 0.998 0.498)
			(stroke
				(width 0.15)
				(type solid)
			)
			(layer "F.Fab")
		)
		(fp_text user "Author: Antmicro"
			(at -1.5 4.5 -90)
			(layer "F.Fab")
			(hide yes)
			(effects
				(font
					(size 0.7 0.7)
					(thickness 0.15)
				)
				(justify left bottom)
			)
		)
		(fp_text user "License: Apache-2.0"
			(at -1.5 5.75 -90)
			(layer "F.Fab")
			(hide yes)
			(effects
				(font
					(size 0.7 0.7)
					(thickness 0.15)
				)
				(justify left bottom)
			)
		)
		(fp_text user "${REFERENCE}"
			(at -1.5 3.25 -90)
			(layer "F.Fab")
			(hide yes)
			(effects
				(font
					(size 0.7 0.7)
					(thickness 0.15)
				)
				(justify left bottom)
			)
		)
		(pad "1" smd roundrect
			(at -0.802 0.45 270)
			(size 0.4 0.5)
			(layers "F.Cu" "F.Paste" "F.Mask")
			(roundrect_rratio 0.25)
			(net 347 "/Peripherals/PCIE3_RST_CONN*")
			(pinfunction "R1.1")
			(pintype "passive")
		)
		(pad "2" smd roundrect
			(at -0.272 0.45 270)
			(size 0.4 0.5)
			(layers "F.Cu" "F.Paste" "F.Mask")
			(roundrect_rratio 0.25)
			(net 513 "/Peripherals/PCIE3_CLKREQ_CONN*")
			(pinfunction "R2.1")
			(pintype "passive")
		)
		(pad "3" smd roundrect
			(at 0.27 0.45 270)
			(size 0.4 0.5)
			(layers "F.Cu" "F.Paste" "F.Mask")
			(roundrect_rratio 0.25)
			(net 578 "/Peripherals/PCIE_WAKE_SEL_EXT_CONN")
			(pinfunction "R3.1")
			(pintype "passive")
		)
		(pad "4" smd roundrect
			(at 0.8 0.45 270)
			(size 0.4 0.5)
			(layers "F.Cu" "F.Paste" "F.Mask")
			(roundrect_rratio 0.25)
			(net 580 "/Peripherals/GPIO13_CONN")
			(pinfunction "R4.1")
			(pintype "passive")
		)
		(pad "5" smd roundrect
			(at 0.8 -0.452 270)
			(size 0.4 0.5)
			(layers "F.Cu" "F.Paste" "F.Mask")
			(roundrect_rratio 0.25)
			(net 84 "GPIO13")
			(pinfunction "R4.2")
			(pintype "passive")
		)
		(pad "6" smd roundrect
			(at 0.27 -0.452 270)
			(size 0.4 0.5)
			(layers "F.Cu" "F.Paste" "F.Mask")
			(roundrect_rratio 0.25)
			(net 427 "PCIE_WAKE_SEL_EXT")
			(pinfunction "R3.2")
			(pintype "passive")
		)
		(pad "7" smd roundrect
			(at -0.272 -0.452 270)
			(size 0.4 0.5)
			(layers "F.Cu" "F.Paste" "F.Mask")
			(roundrect_rratio 0.25)
			(net 128 "PCIE3_CLKREQ*")
			(pinfunction "R2.2")
			(pintype "passive")
		)
		(pad "8" smd roundrect
			(at -0.802 -0.452 270)
			(size 0.4 0.5)
			(layers "F.Cu" "F.Paste" "F.Mask")
			(roundrect_rratio 0.25)
			(net 120 "PCIE3_RST*")
			(pinfunction "R1.2")
			(pintype "passive")
		)
	)
	(footprint "antmicro-footprints:R_0402_1005Metric"
		(layer "F.Cu")
		(at 114.4 99.8 180)
		(descr "Resistor SMD 0402")
		(tags "resistor SMD 0402")
		(property "Reference" "R30"
			(at 3.05 -0.55 180)
			(layer "F.SilkS")
			(effects
				(font
					(size 0.7 0.7)
					(thickness 0.15)
				)
				(justify left bottom)
			)
		)
		(property "Value" "R_0R_0402"
			(at 0 1.4 180)
			(layer "F.Fab")
			(effects
				(font
					(size 0.7 0.7)
					(thickness 0.15)
				)
				(justify left bottom)
			)
		)
		(property "Footprint" "antmicro-footprints:R_0402_1005Metric"
			(at 0 0 180)
			(layer "F.Fab")
			(hide yes)
			(effects
				(font
					(size 1.27 1.27)
					(thickness 0.15)
				)
			)
		)
		(property "Datasheet" "https://industrial.panasonic.com/cdbs/www-data/pdf/RDA0000/AOA0000C301.pdf"
			(at 0 0 180)
			(layer "F.Fab")
			(hide yes)
			(effects
				(font
					(size 1.27 1.27)
					(thickness 0.15)
				)
			)
		)
		(property "Author" "Antmicro"
			(at 228.8 199.6 0)
			(layer "F.Fab")
			(hide yes)
			(effects
				(font
					(size 1 1)
					(thickness 0.15)
				)
			)
		)
		(property "Current" "1A"
			(at 228.8 199.6 0)
			(layer "F.Fab")
			(hide yes)
			(effects
				(font
					(size 1 1)
					(thickness 0.15)
				)
			)
		)
		(property "License" "Apache-2.0"
			(at 228.8 199.6 0)
			(layer "F.Fab")
			(hide yes)
			(effects
				(font
					(size 1 1)
					(thickness 0.15)
				)
			)
		)
		(property "MPN" "ERJ2GE0R00X"
			(at 228.8 199.6 0)
			(layer "F.Fab")
			(hide yes)
			(effects
				(font
					(size 1 1)
					(thickness 0.15)
				)
			)
		)
		(property "Manufacturer" "Panasonic"
			(at 228.8 199.6 0)
			(layer "F.Fab")
			(hide yes)
			(effects
				(font
					(size 1 1)
					(thickness 0.15)
				)
			)
		)
		(property "Tolerance" ""
			(at 228.8 199.6 0)
			(layer "F.Fab")
			(hide yes)
			(effects
				(font
					(size 1 1)
					(thickness 0.15)
				)
			)
		)
		(property "Val" "0R"
			(at 228.8 199.6 0)
			(layer "F.Fab")
			(hide yes)
			(effects
				(font
					(size 1 1)
					(thickness 0.15)
				)
			)
		)
		(sheetname "M.2")
		(sheetfile "m-2.kicad_sch")
		(attr smd exclude_from_pos_files exclude_from_bom dnp)
		(fp_rect
			(start -0.925 -0.47)
			(end 0.925 0.47)
			(stroke
				(width 0.05)
				(type default)
			)
			(fill none)
			(layer "F.CrtYd")
		)
		(fp_rect
			(start -0.5 -0.25)
			(end 0.5 0.25)
			(stroke
				(width 0.15)
				(type solid)
			)
			(fill none)
			(layer "F.Fab")
		)
		(fp_text user "${REFERENCE}"
			(at -0.95 3.168 180)
			(layer "F.Fab")
			(hide yes)
			(effects
				(font
					(size 0.7 0.7)
					(thickness 0.15)
				)
				(justify left bottom)
			)
		)
		(fp_text user "Author: Antmicro"
			(at -0.95 4.169 180)
			(layer "F.Fab")
			(hide yes)
			(effects
				(font
					(size 0.7 0.7)
					(thickness 0.15)
				)
				(justify left bottom)
			)
		)
		(fp_text user "License: Apache-2.0"
			(at -0.95 5.169 180)
			(layer "F.Fab")
			(hide yes)
			(effects
				(font
					(size 0.7 0.7)
					(thickness 0.15)
				)
				(justify left bottom)
			)
		)
		(pad "1" smd roundrect
			(at -0.48 0 180)
			(size 0.59 0.64)
			(layers "F.Cu" "F.Paste" "F.Mask")
			(roundrect_rratio 0.25)
			(net 221 "/M.2/M2_E_I2C_DAT")
			(pintype "passive")
		)
		(pad "2" smd roundrect
			(at 0.48 0 180)
			(size 0.59 0.64)
			(layers "F.Cu" "F.Paste" "F.Mask")
			(roundrect_rratio 0.25)
			(net 251 "SYS_SDA")
			(pintype "passive")
		)
	)
	(footprint "antmicro-footprints:TP_SMD_0.75mm"
		(layer "F.Cu")
		(at 95.55 82.2 180)
		(property "Reference" "TP4"
			(at -0.25 -0.4 180)
			(layer "F.SilkS")
			(effects
				(font
					(size 0.7 0.7)
					(thickness 0.15)
				)
				(justify left bottom)
			)
		)
		(property "Value" "TP_0.75mm_SMD"
			(at 0 1.2 180)
			(layer "F.Fab")
			(effects
				(font
					(size 0.7 0.7)
					(thickness 0.15)
				)
				(justify left bottom)
			)
		)
		(property "Footprint" "antmicro-footprints:TP_SMD_0.75mm"
			(at 0 0 180)
			(layer "F.Fab")
			(hide yes)
			(effects
				(font
					(size 1.27 1.27)
					(thickness 0.15)
				)
			)
		)
		(property "Author" "Antmicro"
			(at 191.1 164.4 0)
			(layer "F.Fab")
			(hide yes)
			(effects
				(font
					(size 1 1)
					(thickness 0.15)
				)
			)
		)
		(property "License" "Apache-2.0"
			(at 191.1 164.4 0)
			(layer "F.Fab")
			(hide yes)
			(effects
				(font
					(size 1 1)
					(thickness 0.15)
				)
			)
		)
		(property "MPN" ""
			(at 191.1 164.4 0)
			(layer "F.Fab")
			(hide yes)
			(effects
				(font
					(size 1 1)
					(thickness 0.15)
				)
			)
		)
		(property "Manufacturer" ""
			(at 191.1 164.4 0)
			(layer "F.Fab")
			(hide yes)
			(effects
				(font
					(size 1 1)
					(thickness 0.15)
				)
			)
		)
		(sheetname "SoM")
		(sheetfile "som.kicad_sch")
		(attr exclude_from_pos_files exclude_from_bom)
		(fp_circle
			(center 0 0)
			(end 0.475 0)
			(stroke
				(width 0.05)
				(type default)
			)
			(fill none)
			(layer "F.CrtYd")
		)
		(fp_text user "${REFERENCE}"
			(at -0.4 2.7 180)
			(layer "F.Fab")
			(hide yes)
			(effects
				(font
					(size 0.7 0.7)
					(thickness 0.15)
				)
				(justify left bottom)
			)
		)
		(fp_text user "License: Apache-2.0"
			(at -0.4 5.101 180)
			(layer "F.Fab")
			(hide yes)
			(effects
				(font
					(size 0.7 0.7)
					(thickness 0.15)
				)
				(justify left bottom)
			)
		)
		(fp_text user "Author: Antmicro"
			(at -0.4 3.901 180)
			(layer "F.Fab")
			(hide yes)
			(effects
				(font
					(size 0.7 0.7)
					(thickness 0.15)
				)
				(justify left bottom)
			)
		)
		(pad "1" smd circle
			(at 0 0 180)
			(size 0.75 0.75)
			(layers "F.Cu" "F.Mask")
			(net 746 "Net-(J15B-CAM1_MCLK)")
			(pinfunction "1")
			(pintype "passive")
		)
	)
	(footprint "antmicro-footprints:C_0402_1005Metric"
		(layer "F.Cu")
		(at 67.2 108.2 90)
		(descr "Capacitor SMD 0402")
		(tags "capacitor SMD 0402")
		(property "Reference" "C49"
			(at -1.1 1.35 90)
			(layer "F.SilkS")
			(effects
				(font
					(size 0.7 0.7)
					(thickness 0.15)
				)
				(justify left bottom)
			)
		)
		(property "Value" "C_10u_0402"
			(at -1.022927 2.155213 90)
			(layer "F.Fab")
			(effects
				(font
					(size 0.7 0.7)
					(thickness 0.15)
				)
				(justify left bottom)
			)
		)
		(property "Footprint" "antmicro-footprints:C_0402_1005Metric"
			(at 0 0 90)
			(layer "F.Fab")
			(hide yes)
			(effects
				(font
					(size 1.27 1.27)
					(thickness 0.15)
				)
			)
		)
		(property "Datasheet" "https://www.yageo.com/en/Chart/Download/pdf/CC0402MRX5R5BB106"
			(at 0 0 90)
			(layer "F.Fab")
			(hide yes)
			(effects
				(font
					(size 1.27 1.27)
					(thickness 0.15)
				)
			)
		)
		(property "Author" "Antmicro"
			(at 175.4 41 0)
			(layer "F.Fab")
			(hide yes)
			(effects
				(font
					(size 1 1)
					(thickness 0.15)
				)
			)
		)
		(property "Dielectric" ""
			(at 175.4 41 0)
			(layer "F.Fab")
			(hide yes)
			(effects
				(font
					(size 1 1)
					(thickness 0.15)
				)
			)
		)
		(property "License" "Apache-2.0"
			(at 175.4 41 0)
			(layer "F.Fab")
			(hide yes)
			(effects
				(font
					(size 1 1)
					(thickness 0.15)
				)
			)
		)
		(property "MPN" "CC0402MRX5R5BB106"
			(at 175.4 41 0)
			(layer "F.Fab")
			(hide yes)
			(effects
				(font
					(size 1 1)
					(thickness 0.15)
				)
			)
		)
		(property "Manufacturer" "YAGEO"
			(at 175.4 41 0)
			(layer "F.Fab")
			(hide yes)
			(effects
				(font
					(size 1 1)
					(thickness 0.15)
				)
			)
		)
		(property "Val" "10u"
			(at 175.4 41 0)
			(layer "F.Fab")
			(hide yes)
			(effects
				(font
					(size 1 1)
					(thickness 0.15)
				)
			)
		)
		(property "Voltage" ""
			(at 175.4 41 0)
			(layer "F.Fab")
			(hide yes)
			(effects
				(font
					(size 1 1)
					(thickness 0.15)
				)
			)
		)
		(sheetname "USB Debug, DP")
		(sheetfile "usb.kicad_sch")
		(attr smd)
		(fp_rect
			(start -0.925 -0.47)
			(end 0.925 0.47)
			(stroke
				(width 0.05)
				(type default)
			)
			(fill none)
			(layer "F.CrtYd")
		)
		(fp_line
			(start 0.504 -0.25)
			(end 0.504 0.248)
			(stroke
				(width 0.15)
				(type solid)
			)
			(layer "F.Fab")
		)
		(fp_line
			(start -0.494 -0.25)
			(end 0.504 -0.25)
			(stroke
				(width 0.15)
				(type solid)
			)
			(layer "F.Fab")
		)
		(fp_line
			(start 0.504 0.248)
			(end -0.494 0.248)
			(stroke
				(width 0.15)
				(type solid)
			)
			(layer "F.Fab")
		)
		(fp_line
			(start -0.494 0.248)
			(end -0.494 -0.25)
			(stroke
				(width 0.15)
				(type solid)
			)
			(layer "F.Fab")
		)
		(fp_text user "License: Apache-2.0"
			(at -0.939 5.799 90)
			(layer "F.Fab")
			(hide yes)
			(effects
				(font
					(size 0.7 0.7)
					(thickness 0.15)
				)
				(justify left bottom)
			)
		)
		(fp_text user "Author: Antmicro"
			(at -0.939 3.399 90)
			(layer "F.Fab")
			(hide yes)
			(effects
				(font
					(size 0.7 0.7)
					(thickness 0.15)
				)
				(justify left bottom)
			)
		)
		(fp_text user "${REFERENCE}"
			(at -0.939 4.599 90)
			(layer "F.Fab")
			(hide yes)
			(effects
				(font
					(size 0.7 0.7)
					(thickness 0.15)
				)
				(justify left bottom)
			)
		)
		(pad "1" smd roundrect
			(at -0.48 0 90)
			(size 0.59 0.64)
			(layers "F.Cu" "F.Paste" "F.Mask")
			(roundrect_rratio 0.25)
			(net 1 "GND")
			(pintype "passive")
		)
		(pad "2" smd roundrect
			(at 0.48 0 90)
			(size 0.59 0.64)
			(layers "F.Cu" "F.Paste" "F.Mask")
			(roundrect_rratio 0.25)
			(net 87 "+3V3")
			(pintype "passive")
		)
	)
)
